(kicad_pcb
	(version 20260206)
	(generator "pcbnew")
	(generator_version "10.0")
	(general
		(thickness 1.6)
		(legacy_teardrops no)
	)
	(paper "A4")
	(title_block
		(title "01162023_DA0F0TEBIF0_F0T_Expander_BD_F_brd_V02_OCP.brd")
		(comment 1 "Grand Teton / footprints 9293-9301 of 9728")
	)
	(layers
		(0 "F.Cu" signal "TOP")
		(4 "In1.Cu" signal "GND")
		(6 "In2.Cu" signal "VCC")
		(8 "In3.Cu" signal "VCC1")
		(10 "In4.Cu" signal "GND1")
		(12 "In5.Cu" signal "IN1")
		(14 "In6.Cu" signal "GND2")
		(16 "In7.Cu" signal "IN2")
		(18 "In8.Cu" signal "GND3")
		(20 "In9.Cu" signal "IN3")
		(22 "In10.Cu" signal "GND4")
		(24 "In11.Cu" signal "IN4")
		(26 "In12.Cu" signal "GND5")
		(28 "In13.Cu" signal "IN5")
		(30 "In14.Cu" signal "GND6")
		(32 "In15.Cu" signal "IN6")
		(34 "In16.Cu" signal "GND7")
		(2 "B.Cu" signal "BOTTOM")
		(9 "F.Adhes" user "F.Adhesive")
		(11 "B.Adhes" user "B.Adhesive")
		(13 "F.Paste" user "Package Geometry/Pastemask Top")
		(15 "B.Paste" user "Package Geometry/Pastemask Bottom")
		(5 "F.SilkS" user "Ref Des/Silkscreen Top")
		(7 "B.SilkS" user "Ref Des/Silkscreen Bottom")
		(1 "F.Mask" user "Board Geometry/Soldermask Top")
		(3 "B.Mask" user "Board Geometry/Soldermask Bottom")
		(17 "Dwgs.User" user "User.Drawings")
		(19 "Cmts.User" user "User.Comments")
		(21 "Eco1.User" user "User.Eco1")
		(23 "Eco2.User" user "User.Eco2")
		(25 "Edge.Cuts" user "Board Geometry/Outline")
		(27 "Margin" user)
		(31 "F.CrtYd" user "Package Geometry/Place Bound Top")
		(29 "B.CrtYd" user "Package Geometry/Place Bound Bottom")
		(35 "F.Fab" user "Ref Des/Assembly Top")
		(33 "B.Fab" user "Ref Des/Assembly Bottom")
	)
	(footprint ""
		(layer "B.Cu")
		(at 59.01817 -153.72461 180)
		(property "Reference" "U10"
			(at 0.7239 -1.901952 0)
			(unlocked yes)
			(layer "B.SilkS")
			(effects
				(font
					(size 0.7874 0.5842)
					(thickness 0.1524)
				)
				(justify mirror)
			)
		)
		(property "Value" ""
			(at 0 0 0)
			(layer "B.Fab")
			(effects
				(font
					(size 1.27 1.27)
				)
				(justify mirror)
			)
		)
		(duplicate_pad_numbers_are_jumpers no)
		(fp_line
			(start 1.684274 1.074928)
			(end 1.684274 -1.074928)
			(stroke
				(width 0.1524)
				(type default)
			)
			(layer "B.SilkS")
		)
		(fp_line
			(start 1.684274 -1.074928)
			(end 0.381 -1.074928)
			(stroke
				(width 0.1524)
				(type default)
			)
			(layer "B.SilkS")
		)
		(fp_line
			(start 0.381 -1.074928)
			(end 0 -0.625094)
			(stroke
				(width 0.1524)
				(type default)
			)
			(layer "B.SilkS")
		)
		(fp_line
			(start 0 -0.625094)
			(end -0.381 -1.074928)
			(stroke
				(width 0.1524)
				(type default)
			)
			(layer "B.SilkS")
		)
		(fp_line
			(start -0.381 -1.074928)
			(end -1.684274 -1.074928)
			(stroke
				(width 0.1524)
				(type default)
			)
			(layer "B.SilkS")
		)
		(fp_line
			(start -1.684274 1.074928)
			(end 1.684274 1.074928)
			(stroke
				(width 0.1524)
				(type default)
			)
			(layer "B.SilkS")
		)
		(fp_line
			(start -1.684274 -1.074928)
			(end -1.684274 1.074928)
			(stroke
				(width 0.1524)
				(type default)
			)
			(layer "B.SilkS")
		)
		(fp_poly
			(pts
				(xy 2.637282 -0.903986) (xy 2.637282 -0.395986) (xy 1.875282 -0.649986)
			)
			(stroke
				(width 0)
				(type default)
			)
			(fill yes)
			(layer "B.SilkS")
		)
		(fp_line
			(start 0.700024 1.074928)
			(end -0.700024 1.074928)
			(stroke
				(width 0.1)
				(type default)
			)
			(layer "B.Fab")
		)
		(fp_line
			(start 0.700024 -1.074928)
			(end 0.700024 1.074928)
			(stroke
				(width 0.1)
				(type default)
			)
			(layer "B.Fab")
		)
		(fp_line
			(start -0.700024 1.074928)
			(end -0.700024 -1.074928)
			(stroke
				(width 0.1)
				(type default)
			)
			(layer "B.Fab")
		)
		(fp_line
			(start -0.700024 -1.074928)
			(end 0.700024 -1.074928)
			(stroke
				(width 0.1)
				(type default)
			)
			(layer "B.Fab")
		)
		(fp_poly
			(pts
				(xy 2.637282 -0.903986) (xy 2.637282 -0.395986) (xy 1.875282 -0.649986)
			)
			(stroke
				(width 0)
				(type default)
			)
			(fill yes)
			(layer "B.Fab")
		)
		(pad "1" smd rect
			(at 1.100074 -0.649986 90)
			(size 0.4064 0.9144)
			(layers "B.Cu" "B.Mask" "B.Paste")
			(net "Net_8456")
		)
		(pad "2" smd rect
			(at 1.100074 0 90)
			(size 0.4064 0.9144)
			(layers "B.Cu" "B.Mask" "B.Paste")
			(net "RST_HP_NIC0_N")
		)
		(pad "3" smd rect
			(at 1.100074 0.649986 90)
			(size 0.4064 0.9144)
			(layers "B.Cu" "B.Mask" "B.Paste")
			(net "GND")
		)
		(pad "4" smd rect
			(at -1.100074 0.649986 90)
			(size 0.4064 0.9144)
			(layers "B.Cu" "B.Mask" "B.Paste")
			(net "RST_HP_NIC0_BUF_N")
		)
		(pad "5" smd rect
			(at -1.100074 -0.649986 90)
			(size 0.4064 0.9144)
			(layers "B.Cu" "B.Mask" "B.Paste")
			(net "P3V3_AUX")
		)
	)
	(footprint ""
		(layer "B.Cu")
		(at 407.949908 -301.599854 -90)
		(property "Reference" "C1989"
			(at 0 0 90)
			(layer "B.SilkS")
			(hide yes)
			(effects
				(font
					(size 1.27 1.27)
				)
				(justify mirror)
			)
		)
		(property "Value" ""
			(at 0 0 90)
			(layer "B.Fab")
			(effects
				(font
					(size 1.27 1.27)
				)
				(justify mirror)
			)
		)
		(duplicate_pad_numbers_are_jumpers no)
		(fp_line
			(start -0.299974 0.150114)
			(end 0.299974 0.150114)
			(stroke
				(width 0.1)
				(type default)
			)
			(layer "B.Fab")
		)
		(fp_line
			(start 0.299974 0.150114)
			(end 0.299974 -0.150114)
			(stroke
				(width 0.1)
				(type default)
			)
			(layer "B.Fab")
		)
		(fp_line
			(start -0.299974 -0.150114)
			(end -0.299974 0.150114)
			(stroke
				(width 0.1)
				(type default)
			)
			(layer "B.Fab")
		)
		(fp_line
			(start 0.299974 -0.150114)
			(end -0.299974 -0.150114)
			(stroke
				(width 0.1)
				(type default)
			)
			(layer "B.Fab")
		)
		(pad "1" smd rect
			(at 0.2667 0 90)
			(size 0.3048 0.381)
			(layers "B.Cu" "B.Mask" "B.Paste")
			(net "P0V8_SERDES_VDDA_PEX3")
		)
		(pad "2" smd rect
			(at -0.2667 0 90)
			(size 0.3048 0.381)
			(layers "B.Cu" "B.Mask" "B.Paste")
			(net "GND")
		)
	)
	(footprint ""
		(layer "B.Cu")
		(at 181.44998 -290.199826 90)
		(property "Reference" "C1427"
			(at 0 0 90)
			(layer "B.SilkS")
			(hide yes)
			(effects
				(font
					(size 1.27 1.27)
				)
				(justify mirror)
			)
		)
		(property "Value" ""
			(at 0 0 90)
			(layer "B.Fab")
			(effects
				(font
					(size 1.27 1.27)
				)
				(justify mirror)
			)
		)
		(duplicate_pad_numbers_are_jumpers no)
		(fp_line
			(start 0.299974 -0.150114)
			(end -0.299974 -0.150114)
			(stroke
				(width 0.1)
				(type default)
			)
			(layer "B.Fab")
		)
		(fp_line
			(start -0.299974 -0.150114)
			(end -0.299974 0.150114)
			(stroke
				(width 0.1)
				(type default)
			)
			(layer "B.Fab")
		)
		(fp_line
			(start 0.299974 0.150114)
			(end 0.299974 -0.150114)
			(stroke
				(width 0.1)
				(type default)
			)
			(layer "B.Fab")
		)
		(fp_line
			(start -0.299974 0.150114)
			(end 0.299974 0.150114)
			(stroke
				(width 0.1)
				(type default)
			)
			(layer "B.Fab")
		)
		(pad "1" smd rect
			(at 0.2667 0 270)
			(size 0.3048 0.381)
			(layers "B.Cu" "B.Mask" "B.Paste")
			(net "P0V8_SERDES_VDDA_PEX1")
		)
		(pad "2" smd rect
			(at -0.2667 0 270)
			(size 0.3048 0.381)
			(layers "B.Cu" "B.Mask" "B.Paste")
			(net "GND")
		)
	)
	(footprint ""
		(layer "B.Cu")
		(at 372.974108 -223.315276 180)
		(property "Reference" "C2504"
			(at 0 0 0)
			(layer "B.SilkS")
			(hide yes)
			(effects
				(font
					(size 1.27 1.27)
				)
				(justify mirror)
			)
		)
		(property "Value" ""
			(at 0 0 0)
			(layer "B.Fab")
			(effects
				(font
					(size 1.27 1.27)
				)
				(justify mirror)
			)
		)
		(duplicate_pad_numbers_are_jumpers no)
		(fp_line
			(start 0.7874 0.4064)
			(end 0.7874 -0.4064)
			(stroke
				(width 0.1524)
				(type default)
			)
			(layer "B.SilkS")
		)
		(fp_line
			(start 0.7874 -0.4064)
			(end -0.7874 -0.4064)
			(stroke
				(width 0.1524)
				(type default)
			)
			(layer "B.SilkS")
		)
		(fp_line
			(start -0.7874 0.4064)
			(end 0.7874 0.4064)
			(stroke
				(width 0.1524)
				(type default)
			)
			(layer "B.SilkS")
		)
		(fp_line
			(start -0.7874 -0.4064)
			(end -0.7874 0.4064)
			(stroke
				(width 0.1524)
				(type default)
			)
			(layer "B.SilkS")
		)
		(fp_line
			(start 0.67945 0.3048)
			(end 0.67945 -0.305054)
			(stroke
				(width 0.1)
				(type default)
			)
			(layer "B.Fab")
		)
		(fp_line
			(start 0.67945 -0.305054)
			(end 0.12065 -0.305054)
			(stroke
				(width 0.1)
				(type default)
			)
			(layer "B.Fab")
		)
		(fp_line
			(start 0.12065 0.3048)
			(end 0.67945 0.3048)
			(stroke
				(width 0.1)
				(type default)
			)
			(layer "B.Fab")
		)
		(fp_line
			(start 0.12065 0.2794)
			(end 0.12065 0.3048)
			(stroke
				(width 0.1)
				(type default)
			)
			(layer "B.Fab")
		)
		(fp_line
			(start 0.12065 -0.2794)
			(end -0.12065 -0.2794)
			(stroke
				(width 0.1)
				(type default)
			)
			(layer "B.Fab")
		)
		(fp_line
			(start 0.12065 -0.305054)
			(end 0.12065 -0.2794)
			(stroke
				(width 0.1)
				(type default)
			)
			(layer "B.Fab")
		)
		(fp_line
			(start -0.120396 0.3048)
			(end -0.120396 0.2794)
			(stroke
				(width 0.1)
				(type default)
			)
			(layer "B.Fab")
		)
		(fp_line
			(start -0.120396 0.2794)
			(end 0.12065 0.2794)
			(stroke
				(width 0.1)
				(type default)
			)
			(layer "B.Fab")
		)
		(fp_line
			(start -0.12065 -0.2794)
			(end -0.12065 -0.3048)
			(stroke
				(width 0.1)
				(type default)
			)
			(layer "B.Fab")
		)
		(fp_line
			(start -0.12065 -0.3048)
			(end -0.67945 -0.3048)
			(stroke
				(width 0.1)
				(type default)
			)
			(layer "B.Fab")
		)
		(fp_line
			(start -0.67945 0.3048)
			(end -0.120396 0.3048)
			(stroke
				(width 0.1)
				(type default)
			)
			(layer "B.Fab")
		)
		(fp_line
			(start -0.67945 -0.3048)
			(end -0.67945 0.3048)
			(stroke
				(width 0.1)
				(type default)
			)
			(layer "B.Fab")
		)
		(pad "1" smd circle
			(at 0.40005 0)
			(size 0 0)
			(layers "B.Cu" "B.Mask" "B.Paste")
			(net "GND")
		)
		(pad "2" smd circle
			(at -0.40005 0)
			(size 0 0)
			(layers "B.Cu" "B.Mask" "B.Paste")
			(net "P1V8_PEX")
		)
	)
	(footprint ""
		(layer "B.Cu")
		(at 2.840736 -382.780032 90)
		(property "Reference" "L150"
			(at 2.087118 0.013462 270)
			(unlocked yes)
			(layer "B.SilkS")
			(effects
				(font
					(size 0.7874 0.5842)
					(thickness 0.1524)
				)
				(justify left mirror)
			)
		)
		(property "Value" ""
			(at 0 0 90)
			(layer "B.Fab")
			(effects
				(font
					(size 1.27 1.27)
				)
				(justify mirror)
			)
		)
		(duplicate_pad_numbers_are_jumpers no)
		(fp_line
			(start 1.63576 -0.8128)
			(end -1.63576 -0.8128)
			(stroke
				(width 0.1524)
				(type default)
			)
			(layer "B.SilkS")
		)
		(fp_line
			(start 1.63576 -0.8128)
			(end 1.63576 0.8128)
			(stroke
				(width 0.1524)
				(type default)
			)
			(layer "B.SilkS")
		)
		(fp_line
			(start -1.63576 -0.8128)
			(end -1.63576 0.8128)
			(stroke
				(width 0.1524)
				(type default)
			)
			(layer "B.SilkS")
		)
		(fp_line
			(start -1.63576 0.8128)
			(end 1.63576 0.8128)
			(stroke
				(width 0.1524)
				(type default)
			)
			(layer "B.SilkS")
		)
		(fp_line
			(start 1.56083 -0.738632)
			(end 1.56083 0.7366)
			(stroke
				(width 0.1)
				(type default)
			)
			(layer "B.Fab")
		)
		(fp_line
			(start -1.560576 -0.738632)
			(end 1.56083 -0.738632)
			(stroke
				(width 0.1)
				(type default)
			)
			(layer "B.Fab")
		)
		(fp_line
			(start 1.56083 0.7366)
			(end 1.524 0.7366)
			(stroke
				(width 0.1)
				(type default)
			)
			(layer "B.Fab")
		)
		(fp_line
			(start 1.524 0.7366)
			(end -1.524 0.7366)
			(stroke
				(width 0.1)
				(type default)
			)
			(layer "B.Fab")
		)
		(fp_line
			(start -1.524 0.7366)
			(end -1.560576 0.7366)
			(stroke
				(width 0.1)
				(type default)
			)
			(layer "B.Fab")
		)
		(fp_line
			(start -1.560576 0.7366)
			(end -1.560576 -0.738632)
			(stroke
				(width 0.1)
				(type default)
			)
			(layer "B.Fab")
		)
		(pad "1" smd rect
			(at 0.94996 0 90)
			(size 1.1176 1.3716)
			(layers "B.Cu" "B.Mask" "B.Paste")
			(net "P3V3_USB_8042")
		)
		(pad "2" smd rect
			(at -0.94996 0 90)
			(size 1.1176 1.3716)
			(layers "B.Cu" "B.Mask" "B.Paste")
			(net "P3V3_USB_HUB")
		)
	)
	(footprint ""
		(layer "B.Cu")
		(at 298.05122 -305.399948 -90)
		(property "Reference" "C3305"
			(at 0 0 90)
			(layer "B.SilkS")
			(hide yes)
			(effects
				(font
					(size 1.27 1.27)
				)
				(justify mirror)
			)
		)
		(property "Value" ""
			(at 0 0 90)
			(layer "B.Fab")
			(effects
				(font
					(size 1.27 1.27)
				)
				(justify mirror)
			)
		)
		(duplicate_pad_numbers_are_jumpers no)
		(fp_line
			(start -0.299974 0.150114)
			(end 0.299974 0.150114)
			(stroke
				(width 0.1)
				(type default)
			)
			(layer "B.Fab")
		)
		(fp_line
			(start 0.299974 0.150114)
			(end 0.299974 -0.150114)
			(stroke
				(width 0.1)
				(type default)
			)
			(layer "B.Fab")
		)
		(fp_line
			(start -0.299974 -0.150114)
			(end -0.299974 0.150114)
			(stroke
				(width 0.1)
				(type default)
			)
			(layer "B.Fab")
		)
		(fp_line
			(start 0.299974 -0.150114)
			(end -0.299974 -0.150114)
			(stroke
				(width 0.1)
				(type default)
			)
			(layer "B.Fab")
		)
		(pad "1" smd rect
			(at 0.2667 0 90)
			(size 0.3048 0.381)
			(layers "B.Cu" "B.Mask" "B.Paste")
			(net "P1V25_SERDES_VDDPLL_PEX2")
		)
		(pad "2" smd rect
			(at -0.2667 0 90)
			(size 0.3048 0.381)
			(layers "B.Cu" "B.Mask" "B.Paste")
			(net "GND")
		)
	)
	(footprint ""
		(layer "B.Cu")
		(at 347.390974 -326.945498 -90)
		(property "Reference" "C4324"
			(at 0 0 90)
			(layer "B.SilkS")
			(hide yes)
			(effects
				(font
					(size 1.27 1.27)
				)
				(justify mirror)
			)
		)
		(property "Value" ""
			(at 0 0 90)
			(layer "B.Fab")
			(effects
				(font
					(size 1.27 1.27)
				)
				(justify mirror)
			)
		)
		(duplicate_pad_numbers_are_jumpers no)
		(fp_line
			(start -1.2954 0.5842)
			(end 1.2954 0.5842)
			(stroke
				(width 0.1524)
				(type default)
			)
			(layer "B.SilkS")
		)
		(fp_line
			(start 1.2954 0.5842)
			(end 1.2954 -0.5842)
			(stroke
				(width 0.1524)
				(type default)
			)
			(layer "B.SilkS")
		)
		(fp_line
			(start -1.2954 -0.5842)
			(end -1.2954 0.5842)
			(stroke
				(width 0.1524)
				(type default)
			)
			(layer "B.SilkS")
		)
		(fp_line
			(start 1.2954 -0.5842)
			(end -1.2954 -0.5842)
			(stroke
				(width 0.1524)
				(type default)
			)
			(layer "B.SilkS")
		)
		(fp_line
			(start -0.8636 0.4572)
			(end 0.8636 0.4572)
			(stroke
				(width 0.1)
				(type default)
			)
			(layer "B.Fab")
		)
		(fp_line
			(start 0.8636 0.4572)
			(end 0.8636 0.4064)
			(stroke
				(width 0.1)
				(type default)
			)
			(layer "B.Fab")
		)
		(fp_line
			(start -1.1938 0.4064)
			(end -0.8636 0.4064)
			(stroke
				(width 0.1)
				(type default)
			)
			(layer "B.Fab")
		)
		(fp_line
			(start -0.8636 0.4064)
			(end -0.8636 0.4572)
			(stroke
				(width 0.1)
				(type default)
			)
			(layer "B.Fab")
		)
		(fp_line
			(start 0.8636 0.4064)
			(end 1.1938 0.4064)
			(stroke
				(width 0.1)
				(type default)
			)
			(layer "B.Fab")
		)
		(fp_line
			(start 1.1938 0.4064)
			(end 1.1938 -0.4064)
			(stroke
				(width 0.1)
				(type default)
			)
			(layer "B.Fab")
		)
		(fp_line
			(start -1.1938 -0.4064)
			(end -1.1938 0.4064)
			(stroke
				(width 0.1)
				(type default)
			)
			(layer "B.Fab")
		)
		(fp_line
			(start -0.8636 -0.4064)
			(end -1.1938 -0.4064)
			(stroke
				(width 0.1)
				(type default)
			)
			(layer "B.Fab")
		)
		(fp_line
			(start 0.8636 -0.4064)
			(end 0.8636 -0.4572)
			(stroke
				(width 0.1)
				(type default)
			)
			(layer "B.Fab")
		)
		(fp_line
			(start 1.1938 -0.4064)
			(end 0.8636 -0.4064)
			(stroke
				(width 0.1)
				(type default)
			)
			(layer "B.Fab")
		)
		(fp_line
			(start -0.8636 -0.4572)
			(end -0.8636 -0.4064)
			(stroke
				(width 0.1)
				(type default)
			)
			(layer "B.Fab")
		)
		(fp_line
			(start 0.8636 -0.4572)
			(end -0.8636 -0.4572)
			(stroke
				(width 0.1)
				(type default)
			)
			(layer "B.Fab")
		)
		(pad "1" smd rect
			(at 0.7366 0 180)
			(size 0.7112 0.8128)
			(layers "B.Cu" "B.Mask" "B.Paste")
			(net "P0V8_SERDES_VDDA_PEX2_C6")
		)
		(pad "2" smd rect
			(at -0.7366 0 180)
			(size 0.7112 0.8128)
			(layers "B.Cu" "B.Mask" "B.Paste")
			(net "GND")
		)
	)
	(footprint ""
		(layer "B.Cu")
		(at 129.23774 -281.024838 90)
		(property "Reference" "PC112"
			(at 0 0 90)
			(layer "B.SilkS")
			(hide yes)
			(effects
				(font
					(size 1.27 1.27)
				)
				(justify mirror)
			)
		)
		(property "Value" ""
			(at 0 0 90)
			(layer "B.Fab")
			(effects
				(font
					(size 1.27 1.27)
				)
				(justify mirror)
			)
		)
		(duplicate_pad_numbers_are_jumpers no)
		(fp_line
			(start 1.524 -0.762)
			(end -1.524 -0.762)
			(stroke
				(width 0.1524)
				(type default)
			)
			(layer "B.SilkS")
		)
		(fp_line
			(start -1.524 -0.762)
			(end -1.524 0.762)
			(stroke
				(width 0.1524)
				(type default)
			)
			(layer "B.SilkS")
		)
		(fp_line
			(start 1.524 0.762)
			(end 1.524 -0.762)
			(stroke
				(width 0.1524)
				(type default)
			)
			(layer "B.SilkS")
		)
		(fp_line
			(start -1.524 0.762)
			(end 1.524 0.762)
			(stroke
				(width 0.1524)
				(type default)
			)
			(layer "B.SilkS")
		)
		(fp_line
			(start 1.1049 -0.724916)
			(end 1.1049 0.724916)
			(stroke
				(width 0.1)
				(type default)
			)
			(layer "B.Fab")
		)
		(fp_line
			(start -1.1049 -0.724916)
			(end 1.1049 -0.724916)
			(stroke
				(width 0.1)
				(type default)
			)
			(layer "B.Fab")
		)
		(fp_line
			(start 1.1049 0.724916)
			(end -1.1049 0.724916)
			(stroke
				(width 0.1)
				(type default)
			)
			(layer "B.Fab")
		)
		(fp_line
			(start -1.1049 0.724916)
			(end -1.1049 -0.724916)
			(stroke
				(width 0.1)
				(type default)
			)
			(layer "B.Fab")
		)
		(pad "1" smd rect
			(at 0.889 0 90)
			(size 1.016 1.27)
			(layers "B.Cu" "B.Mask" "B.Paste")
			(net "SW_P12V_P0V8_PEX1_FLT")
		)
		(pad "2" smd rect
			(at -0.889 0 90)
			(size 1.016 1.27)
			(layers "B.Cu" "B.Mask" "B.Paste")
			(net "GND")
		)
	)
	(footprint ""
		(layer "B.Cu")
		(at 297.570144 -296.37482)
		(property "Reference" "C1632"
			(at 0 0 0)
			(layer "B.SilkS")
			(hide yes)
			(effects
				(font
					(size 1.27 1.27)
				)
				(justify mirror)
			)
		)
		(property "Value" ""
			(at 0 0 0)
			(layer "B.Fab")
			(effects
				(font
					(size 1.27 1.27)
				)
				(justify mirror)
			)
		)
		(duplicate_pad_numbers_are_jumpers no)
		(fp_line
			(start -0.299974 -0.150114)
			(end -0.299974 0.150114)
			(stroke
				(width 0.1)
				(type default)
			)
			(layer "B.Fab")
		)
		(fp_line
			(start -0.299974 0.150114)
			(end 0.299974 0.150114)
			(stroke
				(width 0.1)
				(type default)
			)
			(layer "B.Fab")
		)
		(fp_line
			(start 0.299974 -0.150114)
			(end -0.299974 -0.150114)
			(stroke
				(width 0.1)
				(type default)
			)
			(layer "B.Fab")
		)
		(fp_line
			(start 0.299974 0.150114)
			(end 0.299974 -0.150114)
			(stroke
				(width 0.1)
				(type default)
			)
			(layer "B.Fab")
		)
		(pad "1" smd rect
			(at 0.2667 0 180)
			(size 0.3048 0.381)
			(layers "B.Cu" "B.Mask" "B.Paste")
			(net "P0V8_PEX2")
		)
		(pad "2" smd rect
			(at -0.2667 0 180)
			(size 0.3048 0.381)
			(layers "B.Cu" "B.Mask" "B.Paste")
			(net "GND")
		)
	)
)
